# BASEBOARD_FAB2 (Tioga Pass) — schematic netlist excerpt (pin names and nets, part order shuffled) for the footprints in the layout excerpt that follows; sources: Cadence DE-HDL packaged netlist, KiCad conversion of Wiwynn_Tioga_Pass_MB.brd

R1F8  RES  0.0 5% CHIP  pkg 0402  page 181 : A = FAN_TACH0 ; B = FAN_TACH0_R
R25W87  RES  22.1 1.0% CHIP  pkg 0402  page 147 : A = RMII_BMC_OCP_TXD1_R ; B = RMII_BMC_OCP_TXD1
RF24  RES  1.0K 0.1% CHIP  pkg 0402  page 235 : A = VR_P1V05_PCH_BIREF1 ; B = ISENSE_P1V05_PCH_STBY_PH1_IMON

(kicad_pcb
	(version 20260206)
	(generator "pcbnew")
	(generator_version "10.0")
	(general
		(thickness 1.6)
		(legacy_teardrops no)
	)
	(paper "A4")
	(title_block
		(title "Wiwynn_Tioga_Pass_MB.brd")
		(comment 1 "Tioga Pass / footprints 2058-2060 of 4770")
	)
	(layers
		(0 "F.Cu" signal "TOP")
		(4 "In1.Cu" signal "L2GND")
		(6 "In2.Cu" signal "L3")
		(8 "In3.Cu" signal "L4GND")
		(10 "In4.Cu" signal "L5")
		(12 "In5.Cu" signal "L6GND")
		(14 "In6.Cu" signal "L7VCC")
		(16 "In7.Cu" signal "L8VCC")
		(18 "In8.Cu" signal "L9GND")
		(20 "In9.Cu" signal "L10")
		(22 "In10.Cu" signal "L11GND")
		(24 "In11.Cu" signal "L12")
		(26 "In12.Cu" signal "L13GND")
		(2 "B.Cu" signal "BOTTOM")
		(9 "F.Adhes" user "F.Adhesive")
		(11 "B.Adhes" user "B.Adhesive")
		(13 "F.Paste" user "Package Geometry/Pastemask Top")
		(15 "B.Paste" user "Package Geometry/Pastemask Bottom")
		(5 "F.SilkS" user "Ref Des/Silkscreen Top")
		(7 "B.SilkS" user "Ref Des/Silkscreen Bottom")
		(1 "F.Mask" user "Board Geometry/Soldermask Top")
		(3 "B.Mask" user "Board Geometry/Soldermask Bottom")
		(17 "Dwgs.User" user "User.Drawings")
		(19 "Cmts.User" user "User.Comments")
		(21 "Eco1.User" user "User.Eco1")
		(23 "Eco2.User" user "User.Eco2")
		(25 "Edge.Cuts" user "Board Geometry/Outline")
		(27 "Margin" user)
		(31 "F.CrtYd" user "Package Geometry/Place Bound Top")
		(29 "B.CrtYd" user "Package Geometry/Place Bound Bottom")
		(35 "F.Fab" user "Ref Des/Assembly Top")
		(33 "B.Fab" user "Ref Des/Assembly Bottom")
	)
	(footprint ""
		(layer "F.Cu")
		(at 13.1572 -40.005 -90)
		(property "Reference" "R1F8"
			(at 0 0 270)
			(layer "F.SilkS")
			(hide yes)
			(effects
				(font
					(size 1.27 1.27)
				)
			)
		)
		(property "Value" ""
			(at 0 0 270)
			(layer "F.Fab")
			(effects
				(font
					(size 1.27 1.27)
				)
			)
		)
		(duplicate_pad_numbers_are_jumpers no)
		(fp_poly
			(pts
				(xy -0.2794 -0.1016) (xy 0.2794 -0.1016) (xy 0.2794 0.9906) (xy -0.2794 0.9906)
			)
			(stroke
				(width 0)
				(type default)
			)
			(fill no)
			(layer "F.CrtYd")
		)
		(fp_line
			(start -0.2794 0.9906)
			(end 0.2794 0.9906)
			(stroke
				(width 0.1)
				(type default)
			)
			(layer "F.Fab")
		)
		(fp_line
			(start 0.2794 0.9906)
			(end 0.2794 -0.1016)
			(stroke
				(width 0.1)
				(type default)
			)
			(layer "F.Fab")
		)
		(fp_line
			(start -0.2794 -0.1016)
			(end -0.2794 0.9906)
			(stroke
				(width 0.1)
				(type default)
			)
			(layer "F.Fab")
		)
		(fp_line
			(start 0.2794 -0.1016)
			(end -0.2794 -0.1016)
			(stroke
				(width 0.1)
				(type default)
			)
			(layer "F.Fab")
		)
		(pad "1" smd rect
			(at 0 0 270)
			(size 0.508 0.508)
			(layers "F.Cu" "F.Mask" "F.Paste")
			(net "FAN_TACH0")
		)
		(pad "2" smd rect
			(at 0 0.889 270)
			(size 0.508 0.508)
			(layers "F.Cu" "F.Mask" "F.Paste")
			(net "FAN_TACH0_R")
		)
		(zone
			(layer "F.Cu")
			(hatch none 0.5)
			(connect_pads
				(clearance 0)
			)
			(min_thickness 0.25)
			(keepout
				(tracks not_allowed)
				(vias allowed)
				(pads allowed)
				(copperpour not_allowed)
				(footprints allowed)
			)
			(placement
				(enabled no)
				(sheetname "")
			)
			(fill
				(thermal_gap 0.5)
				(thermal_bridge_width 0.5)
				(island_removal_mode 0)
			)
			(polygon
				(pts
					(xy 12.5222 -40.259) (xy 12.5222 -39.751) (xy 12.9032 -39.751) (xy 12.9032 -40.259)
				)
			)
		)
		(zone
			(layer "F.Cu")
			(hatch none 0.5)
			(connect_pads
				(clearance 0)
			)
			(min_thickness 0.25)
			(keepout
				(tracks allowed)
				(vias not_allowed)
				(pads allowed)
				(copperpour not_allowed)
				(footprints allowed)
			)
			(placement
				(enabled no)
				(sheetname "")
			)
			(fill
				(thermal_gap 0.5)
				(thermal_bridge_width 0.5)
				(island_removal_mode 0)
			)
			(polygon
				(pts
					(xy 12.9032 -40.259) (xy 12.9032 -39.751) (xy 12.5222 -39.751) (xy 12.5222 -40.259)
				)
			)
		)
	)
	(footprint ""
		(layer "F.Cu")
		(at 402.382482 -29.382466)
		(property "Reference" "R25W87"
			(at -0.8382 -0.67818 0)
			(unlocked yes)
			(layer "F.SilkS")
			(effects
				(font
					(size 0.4064 0.254)
					(thickness 0.1524)
				)
				(justify left)
			)
		)
		(property "Value" ""
			(at 0 0 0)
			(layer "F.Fab")
			(effects
				(font
					(size 1.27 1.27)
				)
			)
		)
		(duplicate_pad_numbers_are_jumpers no)
		(fp_poly
			(pts
				(xy -0.2794 -0.1016) (xy 0.2794 -0.1016) (xy 0.2794 0.9906) (xy -0.2794 0.9906)
			)
			(stroke
				(width 0)
				(type default)
			)
			(fill no)
			(layer "F.CrtYd")
		)
		(fp_line
			(start -0.2794 -0.1016)
			(end -0.2794 0.9906)
			(stroke
				(width 0.1)
				(type default)
			)
			(layer "F.Fab")
		)
		(fp_line
			(start -0.2794 0.9906)
			(end 0.2794 0.9906)
			(stroke
				(width 0.1)
				(type default)
			)
			(layer "F.Fab")
		)
		(fp_line
			(start 0.2794 -0.1016)
			(end -0.2794 -0.1016)
			(stroke
				(width 0.1)
				(type default)
			)
			(layer "F.Fab")
		)
		(fp_line
			(start 0.2794 0.9906)
			(end 0.2794 -0.1016)
			(stroke
				(width 0.1)
				(type default)
			)
			(layer "F.Fab")
		)
		(pad "1" smd rect
			(at 0 0)
			(size 0.508 0.508)
			(layers "F.Cu" "F.Mask" "F.Paste")
			(net "RMII_BMC_OCP_TXD1_R")
		)
		(pad "2" smd rect
			(at 0 0.889)
			(size 0.508 0.508)
			(layers "F.Cu" "F.Mask" "F.Paste")
			(net "RMII_BMC_OCP_TXD1")
		)
		(zone
			(layer "F.Cu")
			(hatch none 0.5)
			(connect_pads
				(clearance 0)
			)
			(min_thickness 0.25)
			(keepout
				(tracks allowed)
				(vias not_allowed)
				(pads allowed)
				(copperpour not_allowed)
				(footprints allowed)
			)
			(placement
				(enabled no)
				(sheetname "")
			)
			(fill
				(thermal_gap 0.5)
				(thermal_bridge_width 0.5)
				(island_removal_mode 0)
			)
			(polygon
				(pts
					(xy 402.128482 -29.128466) (xy 402.636482 -29.128466) (xy 402.636482 -28.747466) (xy 402.128482 -28.747466)
				)
			)
		)
		(zone
			(layer "F.Cu")
			(hatch none 0.5)
			(connect_pads
				(clearance 0)
			)
			(min_thickness 0.25)
			(keepout
				(tracks not_allowed)
				(vias allowed)
				(pads allowed)
				(copperpour not_allowed)
				(footprints allowed)
			)
			(placement
				(enabled no)
				(sheetname "")
			)
			(fill
				(thermal_gap 0.5)
				(thermal_bridge_width 0.5)
				(island_removal_mode 0)
			)
			(polygon
				(pts
					(xy 402.128482 -28.747466) (xy 402.636482 -28.747466) (xy 402.636482 -29.128466) (xy 402.128482 -29.128466)
				)
			)
		)
	)
	(footprint ""
		(layer "F.Cu")
		(at 396.515082 -157.707076 -90)
		(property "Reference" "RF24"
			(at -0.8382 -0.67818 270)
			(unlocked yes)
			(layer "F.SilkS")
			(effects
				(font
					(size 0.4064 0.254)
					(thickness 0.1524)
				)
				(justify left)
			)
		)
		(property "Value" ""
			(at 0 0 270)
			(layer "F.Fab")
			(effects
				(font
					(size 1.27 1.27)
				)
			)
		)
		(duplicate_pad_numbers_are_jumpers no)
		(fp_poly
			(pts
				(xy -0.2794 -0.1016) (xy 0.2794 -0.1016) (xy 0.2794 0.9906) (xy -0.2794 0.9906)
			)
			(stroke
				(width 0)
				(type default)
			)
			(fill no)
			(layer "F.CrtYd")
		)
		(fp_line
			(start -0.2794 0.9906)
			(end 0.2794 0.9906)
			(stroke
				(width 0.1)
				(type default)
			)
			(layer "F.Fab")
		)
		(fp_line
			(start 0.2794 0.9906)
			(end 0.2794 -0.1016)
			(stroke
				(width 0.1)
				(type default)
			)
			(layer "F.Fab")
		)
		(fp_line
			(start -0.2794 -0.1016)
			(end -0.2794 0.9906)
			(stroke
				(width 0.1)
				(type default)
			)
			(layer "F.Fab")
		)
		(fp_line
			(start 0.2794 -0.1016)
			(end -0.2794 -0.1016)
			(stroke
				(width 0.1)
				(type default)
			)
			(layer "F.Fab")
		)
		(pad "1" smd rect
			(at 0 0 270)
			(size 0.508 0.508)
			(layers "F.Cu" "F.Mask" "F.Paste")
			(net "VR_P1V05_PCH_BIREF1")
		)
		(pad "2" smd rect
			(at 0 0.889 270)
			(size 0.508 0.508)
			(layers "F.Cu" "F.Mask" "F.Paste")
			(net "ISENSE_P1V05_PCH_STBY_PH1_IMON")
		)
		(zone
			(layer "F.Cu")
			(hatch none 0.5)
			(connect_pads
				(clearance 0)
			)
			(min_thickness 0.25)
			(keepout
				(tracks not_allowed)
				(vias allowed)
				(pads allowed)
				(copperpour not_allowed)
				(footprints allowed)
			)
			(placement
				(enabled no)
				(sheetname "")
			)
			(fill
				(thermal_gap 0.5)
				(thermal_bridge_width 0.5)
				(island_removal_mode 0)
			)
			(polygon
				(pts
					(xy 395.880082 -157.961076) (xy 395.880082 -157.453076) (xy 396.261082 -157.453076) (xy 396.261082 -157.961076)
				)
			)
		)
		(zone
			(layer "F.Cu")
			(hatch none 0.5)
			(connect_pads
				(clearance 0)
			)
			(min_thickness 0.25)
			(keepout
				(tracks allowed)
				(vias not_allowed)
				(pads allowed)
				(copperpour not_allowed)
				(footprints allowed)
			)
			(placement
				(enabled no)
				(sheetname "")
			)
			(fill
				(thermal_gap 0.5)
				(thermal_bridge_width 0.5)
				(island_removal_mode 0)
			)
			(polygon
				(pts
					(xy 396.261082 -157.961076) (xy 396.261082 -157.453076) (xy 395.880082 -157.453076) (xy 395.880082 -157.961076)
				)
			)
		)
	)
)
